(kicad_pcb
	(version 20260206)
	(generator "pcbnew")
	(generator_version "10.0")
	(general
		(thickness 1.6)
		(legacy_teardrops no)
	)
	(paper "A4")
	(title_block
		(title "01162023_DA0F0TEBIF0_F0T_Expander_BD_F_brd_V02_OCP.brd")
		(comment 1 "Grand Teton / footprints 1888-1893 of 9728")
	)
	(layers
		(0 "F.Cu" signal "TOP")
		(4 "In1.Cu" signal "GND")
		(6 "In2.Cu" signal "VCC")
		(8 "In3.Cu" signal "VCC1")
		(10 "In4.Cu" signal "GND1")
		(12 "In5.Cu" signal "IN1")
		(14 "In6.Cu" signal "GND2")
		(16 "In7.Cu" signal "IN2")
		(18 "In8.Cu" signal "GND3")
		(20 "In9.Cu" signal "IN3")
		(22 "In10.Cu" signal "GND4")
		(24 "In11.Cu" signal "IN4")
		(26 "In12.Cu" signal "GND5")
		(28 "In13.Cu" signal "IN5")
		(30 "In14.Cu" signal "GND6")
		(32 "In15.Cu" signal "IN6")
		(34 "In16.Cu" signal "GND7")
		(2 "B.Cu" signal "BOTTOM")
		(9 "F.Adhes" user "F.Adhesive")
		(11 "B.Adhes" user "B.Adhesive")
		(13 "F.Paste" user "Package Geometry/Pastemask Top")
		(15 "B.Paste" user "Package Geometry/Pastemask Bottom")
		(5 "F.SilkS" user "Ref Des/Silkscreen Top")
		(7 "B.SilkS" user "Ref Des/Silkscreen Bottom")
		(1 "F.Mask" user "Board Geometry/Soldermask Top")
		(3 "B.Mask" user "Board Geometry/Soldermask Bottom")
		(17 "Dwgs.User" user "User.Drawings")
		(19 "Cmts.User" user "User.Comments")
		(21 "Eco1.User" user "User.Eco1")
		(23 "Eco2.User" user "User.Eco2")
		(25 "Edge.Cuts" user "Board Geometry/Outline")
		(27 "Margin" user)
		(31 "F.CrtYd" user "Package Geometry/Place Bound Top")
		(29 "B.CrtYd" user "Package Geometry/Place Bound Bottom")
		(35 "F.Fab" user "Ref Des/Assembly Top")
		(33 "B.Fab" user "Ref Des/Assembly Bottom")
	)
	(footprint ""
		(layer "F.Cu")
		(at 32.575754 -36.915598 -90)
		(property "Reference" "R5544"
			(at 0 0 270)
			(layer "F.SilkS")
			(hide yes)
			(effects
				(font
					(size 1.27 1.27)
				)
			)
		)
		(property "Value" ""
			(at 0 0 270)
			(layer "F.Fab")
			(effects
				(font
					(size 1.27 1.27)
				)
			)
		)
		(duplicate_pad_numbers_are_jumpers no)
		(fp_line
			(start -0.7874 0.4064)
			(end -0.7874 -0.4064)
			(stroke
				(width 0.1524)
				(type default)
			)
			(layer "F.SilkS")
		)
		(fp_line
			(start 0.7874 0.4064)
			(end -0.7874 0.4064)
			(stroke
				(width 0.1524)
				(type default)
			)
			(layer "F.SilkS")
		)
		(fp_line
			(start -0.7874 -0.4064)
			(end 0.7874 -0.4064)
			(stroke
				(width 0.1524)
				(type default)
			)
			(layer "F.SilkS")
		)
		(fp_line
			(start 0.7874 -0.4064)
			(end 0.7874 0.4064)
			(stroke
				(width 0.1524)
				(type default)
			)
			(layer "F.SilkS")
		)
		(fp_line
			(start -0.67945 0.3048)
			(end -0.67945 -0.305054)
			(stroke
				(width 0.1)
				(type default)
			)
			(layer "F.Fab")
		)
		(fp_line
			(start -0.12065 0.3048)
			(end -0.67945 0.3048)
			(stroke
				(width 0.1)
				(type default)
			)
			(layer "F.Fab")
		)
		(fp_line
			(start 0.120396 0.3048)
			(end 0.120396 0.2794)
			(stroke
				(width 0.1)
				(type default)
			)
			(layer "F.Fab")
		)
		(fp_line
			(start 0.67945 0.3048)
			(end 0.120396 0.3048)
			(stroke
				(width 0.1)
				(type default)
			)
			(layer "F.Fab")
		)
		(fp_line
			(start -0.12065 0.2794)
			(end -0.12065 0.3048)
			(stroke
				(width 0.1)
				(type default)
			)
			(layer "F.Fab")
		)
		(fp_line
			(start 0.120396 0.2794)
			(end -0.12065 0.2794)
			(stroke
				(width 0.1)
				(type default)
			)
			(layer "F.Fab")
		)
		(fp_line
			(start -0.12065 -0.2794)
			(end 0.12065 -0.2794)
			(stroke
				(width 0.1)
				(type default)
			)
			(layer "F.Fab")
		)
		(fp_line
			(start 0.12065 -0.2794)
			(end 0.12065 -0.3048)
			(stroke
				(width 0.1)
				(type default)
			)
			(layer "F.Fab")
		)
		(fp_line
			(start 0.12065 -0.3048)
			(end 0.67945 -0.3048)
			(stroke
				(width 0.1)
				(type default)
			)
			(layer "F.Fab")
		)
		(fp_line
			(start 0.67945 -0.3048)
			(end 0.67945 0.3048)
			(stroke
				(width 0.1)
				(type default)
			)
			(layer "F.Fab")
		)
		(fp_line
			(start -0.67945 -0.305054)
			(end -0.12065 -0.305054)
			(stroke
				(width 0.1)
				(type default)
			)
			(layer "F.Fab")
		)
		(fp_line
			(start -0.12065 -0.305054)
			(end -0.12065 -0.2794)
			(stroke
				(width 0.1)
				(type default)
			)
			(layer "F.Fab")
		)
		(pad "1" smd circle
			(at -0.40005 0 270)
			(size 0 0)
			(layers "F.Cu" "F.Mask" "F.Paste")
			(net "PRSNT_SSD1_R1_N")
		)
		(pad "2" smd circle
			(at 0.40005 0 270)
			(size 0 0)
			(layers "F.Cu" "F.Mask" "F.Paste")
			(net "PRSNT_SSD1_R_N")
		)
	)
	(footprint ""
		(layer "F.Cu")
		(at 2.87528 -64.102234)
		(property "Reference" "R5842"
			(at 0 0 0)
			(layer "F.SilkS")
			(hide yes)
			(effects
				(font
					(size 1.27 1.27)
				)
			)
		)
		(property "Value" ""
			(at 0 0 0)
			(layer "F.Fab")
			(effects
				(font
					(size 1.27 1.27)
				)
			)
		)
		(duplicate_pad_numbers_are_jumpers no)
		(fp_line
			(start -0.7874 -0.4064)
			(end 0.7874 -0.4064)
			(stroke
				(width 0.1524)
				(type default)
			)
			(layer "F.SilkS")
		)
		(fp_line
			(start -0.7874 0.4064)
			(end -0.7874 -0.4064)
			(stroke
				(width 0.1524)
				(type default)
			)
			(layer "F.SilkS")
		)
		(fp_line
			(start 0.7874 -0.4064)
			(end 0.7874 0.4064)
			(stroke
				(width 0.1524)
				(type default)
			)
			(layer "F.SilkS")
		)
		(fp_line
			(start 0.7874 0.4064)
			(end -0.7874 0.4064)
			(stroke
				(width 0.1524)
				(type default)
			)
			(layer "F.SilkS")
		)
		(fp_line
			(start -0.67945 -0.305054)
			(end -0.12065 -0.305054)
			(stroke
				(width 0.1)
				(type default)
			)
			(layer "F.Fab")
		)
		(fp_line
			(start -0.67945 0.3048)
			(end -0.67945 -0.305054)
			(stroke
				(width 0.1)
				(type default)
			)
			(layer "F.Fab")
		)
		(fp_line
			(start -0.12065 -0.305054)
			(end -0.12065 -0.2794)
			(stroke
				(width 0.1)
				(type default)
			)
			(layer "F.Fab")
		)
		(fp_line
			(start -0.12065 -0.2794)
			(end 0.12065 -0.2794)
			(stroke
				(width 0.1)
				(type default)
			)
			(layer "F.Fab")
		)
		(fp_line
			(start -0.12065 0.2794)
			(end -0.12065 0.3048)
			(stroke
				(width 0.1)
				(type default)
			)
			(layer "F.Fab")
		)
		(fp_line
			(start -0.12065 0.3048)
			(end -0.67945 0.3048)
			(stroke
				(width 0.1)
				(type default)
			)
			(layer "F.Fab")
		)
		(fp_line
			(start 0.120396 0.2794)
			(end -0.12065 0.2794)
			(stroke
				(width 0.1)
				(type default)
			)
			(layer "F.Fab")
		)
		(fp_line
			(start 0.120396 0.3048)
			(end 0.120396 0.2794)
			(stroke
				(width 0.1)
				(type default)
			)
			(layer "F.Fab")
		)
		(fp_line
			(start 0.12065 -0.3048)
			(end 0.67945 -0.3048)
			(stroke
				(width 0.1)
				(type default)
			)
			(layer "F.Fab")
		)
		(fp_line
			(start 0.12065 -0.2794)
			(end 0.12065 -0.3048)
			(stroke
				(width 0.1)
				(type default)
			)
			(layer "F.Fab")
		)
		(fp_line
			(start 0.67945 -0.3048)
			(end 0.67945 0.3048)
			(stroke
				(width 0.1)
				(type default)
			)
			(layer "F.Fab")
		)
		(fp_line
			(start 0.67945 0.3048)
			(end 0.120396 0.3048)
			(stroke
				(width 0.1)
				(type default)
			)
			(layer "F.Fab")
		)
		(pad "1" smd circle
			(at -0.40005 0)
			(size 0 0)
			(layers "F.Cu" "F.Mask" "F.Paste")
			(net "P12V_SSD0_R")
		)
		(pad "2" smd circle
			(at 0.40005 0)
			(size 0 0)
			(layers "F.Cu" "F.Mask" "F.Paste")
			(net "P12V_SSD0_PG_G1")
		)
	)
	(footprint ""
		(layer "F.Cu")
		(at 431.147728 -40.037258 90)
		(property "Reference" "U378"
			(at 0.247142 2.431542 90)
			(unlocked yes)
			(layer "F.SilkS")
			(effects
				(font
					(size 0.7874 0.5842)
					(thickness 0.1524)
				)
			)
		)
		(property "Value" ""
			(at 0 0 90)
			(layer "F.Fab")
			(effects
				(font
					(size 1.27 1.27)
				)
			)
		)
		(duplicate_pad_numbers_are_jumpers no)
		(fp_line
			(start -1.949958 -1.610106)
			(end 1.949958 -1.610106)
			(stroke
				(width 0.1524)
				(type default)
			)
			(layer "F.SilkS")
		)
		(fp_line
			(start 1.949958 -1.560068)
			(end 1.949958 1.610106)
			(stroke
				(width 0.1524)
				(type default)
			)
			(layer "F.SilkS")
		)
		(fp_line
			(start 1.949958 1.610106)
			(end -1.949958 1.610106)
			(stroke
				(width 0.1524)
				(type default)
			)
			(layer "F.SilkS")
		)
		(fp_line
			(start -1.949958 1.610106)
			(end -1.949958 -1.610106)
			(stroke
				(width 0.1524)
				(type default)
			)
			(layer "F.SilkS")
		)
		(fp_line
			(start 0.750062 -1.560068)
			(end 0.750062 1.560068)
			(stroke
				(width 0.1)
				(type default)
			)
			(layer "F.Fab")
		)
		(fp_line
			(start -0.750062 -1.560068)
			(end 0.750062 -1.560068)
			(stroke
				(width 0.1)
				(type default)
			)
			(layer "F.Fab")
		)
		(fp_line
			(start 0.750062 1.560068)
			(end -0.750062 1.560068)
			(stroke
				(width 0.1)
				(type default)
			)
			(layer "F.Fab")
		)
		(fp_line
			(start -0.750062 1.560068)
			(end -0.750062 -1.560068)
			(stroke
				(width 0.1)
				(type default)
			)
			(layer "F.Fab")
		)
		(pad "D" smd rect
			(at 1.100074 0)
			(size 1.016 1.4224)
			(layers "F.Cu" "F.Mask" "F.Paste")
			(net "SSD15_AUX_P3V3_EN")
		)
		(pad "G" smd rect
			(at -1.100074 -0.94996)
			(size 1.016 1.4224)
			(layers "F.Cu" "F.Mask" "F.Paste")
			(net "PRSNT_SSD15_R1_N")
		)
		(pad "S" smd rect
			(at -1.100074 0.94996)
			(size 1.016 1.4224)
			(layers "F.Cu" "F.Mask" "F.Paste")
			(net "GND")
		)
	)
	(footprint ""
		(layer "F.Cu")
		(at 335.534 -201.168 -90)
		(property "Reference" "R4125"
			(at 0 0 270)
			(layer "F.SilkS")
			(hide yes)
			(effects
				(font
					(size 1.27 1.27)
				)
			)
		)
		(property "Value" ""
			(at 0 0 270)
			(layer "F.Fab")
			(effects
				(font
					(size 1.27 1.27)
				)
			)
		)
		(duplicate_pad_numbers_are_jumpers no)
		(fp_line
			(start -0.7874 0.4064)
			(end -0.7874 -0.4064)
			(stroke
				(width 0.1524)
				(type default)
			)
			(layer "F.SilkS")
		)
		(fp_line
			(start 0.7874 0.4064)
			(end -0.7874 0.4064)
			(stroke
				(width 0.1524)
				(type default)
			)
			(layer "F.SilkS")
		)
		(fp_line
			(start -0.7874 -0.4064)
			(end 0.7874 -0.4064)
			(stroke
				(width 0.1524)
				(type default)
			)
			(layer "F.SilkS")
		)
		(fp_line
			(start 0.7874 -0.4064)
			(end 0.7874 0.4064)
			(stroke
				(width 0.1524)
				(type default)
			)
			(layer "F.SilkS")
		)
		(fp_line
			(start -0.67945 0.3048)
			(end -0.67945 -0.305054)
			(stroke
				(width 0.1)
				(type default)
			)
			(layer "F.Fab")
		)
		(fp_line
			(start -0.12065 0.3048)
			(end -0.67945 0.3048)
			(stroke
				(width 0.1)
				(type default)
			)
			(layer "F.Fab")
		)
		(fp_line
			(start 0.120396 0.3048)
			(end 0.120396 0.2794)
			(stroke
				(width 0.1)
				(type default)
			)
			(layer "F.Fab")
		)
		(fp_line
			(start 0.67945 0.3048)
			(end 0.120396 0.3048)
			(stroke
				(width 0.1)
				(type default)
			)
			(layer "F.Fab")
		)
		(fp_line
			(start -0.12065 0.2794)
			(end -0.12065 0.3048)
			(stroke
				(width 0.1)
				(type default)
			)
			(layer "F.Fab")
		)
		(fp_line
			(start 0.120396 0.2794)
			(end -0.12065 0.2794)
			(stroke
				(width 0.1)
				(type default)
			)
			(layer "F.Fab")
		)
		(fp_line
			(start -0.12065 -0.2794)
			(end 0.12065 -0.2794)
			(stroke
				(width 0.1)
				(type default)
			)
			(layer "F.Fab")
		)
		(fp_line
			(start 0.12065 -0.2794)
			(end 0.12065 -0.3048)
			(stroke
				(width 0.1)
				(type default)
			)
			(layer "F.Fab")
		)
		(fp_line
			(start 0.12065 -0.3048)
			(end 0.67945 -0.3048)
			(stroke
				(width 0.1)
				(type default)
			)
			(layer "F.Fab")
		)
		(fp_line
			(start 0.67945 -0.3048)
			(end 0.67945 0.3048)
			(stroke
				(width 0.1)
				(type default)
			)
			(layer "F.Fab")
		)
		(fp_line
			(start -0.67945 -0.305054)
			(end -0.12065 -0.305054)
			(stroke
				(width 0.1)
				(type default)
			)
			(layer "F.Fab")
		)
		(fp_line
			(start -0.12065 -0.305054)
			(end -0.12065 -0.2794)
			(stroke
				(width 0.1)
				(type default)
			)
			(layer "F.Fab")
		)
		(pad "1" smd circle
			(at -0.40005 0 270)
			(size 0 0)
			(layers "F.Cu" "F.Mask" "F.Paste")
			(net "RST_SSD10_PERST_N")
		)
		(pad "2" smd circle
			(at 0.40005 0 270)
			(size 0 0)
			(layers "F.Cu" "F.Mask" "F.Paste")
			(net "RST_SSD10_PERST_R_N")
		)
	)
	(footprint ""
		(layer "F.Cu")
		(at 271.782286 -252.356874 -90)
		(property "Reference" "R3963"
			(at 0 0 270)
			(layer "F.SilkS")
			(hide yes)
			(effects
				(font
					(size 1.27 1.27)
				)
			)
		)
		(property "Value" ""
			(at 0 0 270)
			(layer "F.Fab")
			(effects
				(font
					(size 1.27 1.27)
				)
			)
		)
		(duplicate_pad_numbers_are_jumpers no)
		(fp_line
			(start -0.7874 0.4064)
			(end -0.7874 -0.4064)
			(stroke
				(width 0.1524)
				(type default)
			)
			(layer "F.SilkS")
		)
		(fp_line
			(start 0.7874 0.4064)
			(end -0.7874 0.4064)
			(stroke
				(width 0.1524)
				(type default)
			)
			(layer "F.SilkS")
		)
		(fp_line
			(start -0.7874 -0.4064)
			(end 0.7874 -0.4064)
			(stroke
				(width 0.1524)
				(type default)
			)
			(layer "F.SilkS")
		)
		(fp_line
			(start 0.7874 -0.4064)
			(end 0.7874 0.4064)
			(stroke
				(width 0.1524)
				(type default)
			)
			(layer "F.SilkS")
		)
		(fp_line
			(start -0.67945 0.3048)
			(end -0.67945 -0.305054)
			(stroke
				(width 0.1)
				(type default)
			)
			(layer "F.Fab")
		)
		(fp_line
			(start -0.12065 0.3048)
			(end -0.67945 0.3048)
			(stroke
				(width 0.1)
				(type default)
			)
			(layer "F.Fab")
		)
		(fp_line
			(start 0.120396 0.3048)
			(end 0.120396 0.2794)
			(stroke
				(width 0.1)
				(type default)
			)
			(layer "F.Fab")
		)
		(fp_line
			(start 0.67945 0.3048)
			(end 0.120396 0.3048)
			(stroke
				(width 0.1)
				(type default)
			)
			(layer "F.Fab")
		)
		(fp_line
			(start -0.12065 0.2794)
			(end -0.12065 0.3048)
			(stroke
				(width 0.1)
				(type default)
			)
			(layer "F.Fab")
		)
		(fp_line
			(start 0.120396 0.2794)
			(end -0.12065 0.2794)
			(stroke
				(width 0.1)
				(type default)
			)
			(layer "F.Fab")
		)
		(fp_line
			(start -0.12065 -0.2794)
			(end 0.12065 -0.2794)
			(stroke
				(width 0.1)
				(type default)
			)
			(layer "F.Fab")
		)
		(fp_line
			(start 0.12065 -0.2794)
			(end 0.12065 -0.3048)
			(stroke
				(width 0.1)
				(type default)
			)
			(layer "F.Fab")
		)
		(fp_line
			(start 0.12065 -0.3048)
			(end 0.67945 -0.3048)
			(stroke
				(width 0.1)
				(type default)
			)
			(layer "F.Fab")
		)
		(fp_line
			(start 0.67945 -0.3048)
			(end 0.67945 0.3048)
			(stroke
				(width 0.1)
				(type default)
			)
			(layer "F.Fab")
		)
		(fp_line
			(start -0.67945 -0.305054)
			(end -0.12065 -0.305054)
			(stroke
				(width 0.1)
				(type default)
			)
			(layer "F.Fab")
		)
		(fp_line
			(start -0.12065 -0.305054)
			(end -0.12065 -0.2794)
			(stroke
				(width 0.1)
				(type default)
			)
			(layer "F.Fab")
		)
		(pad "1" smd circle
			(at -0.40005 0 270)
			(size 0 0)
			(layers "F.Cu" "F.Mask" "F.Paste")
			(net "PEX2_PCA9555_INT_R_N")
		)
		(pad "2" smd circle
			(at 0.40005 0 270)
			(size 0 0)
			(layers "F.Cu" "F.Mask" "F.Paste")
			(net "P1V8_PEX")
		)
	)
	(footprint ""
		(layer "F.Cu")
		(at 146.18208 -286.590232 180)
		(property "Reference" "C3235"
			(at 0 0 180)
			(layer "F.SilkS")
			(hide yes)
			(effects
				(font
					(size 1.27 1.27)
				)
			)
		)
		(property "Value" ""
			(at 0 0 180)
			(layer "F.Fab")
			(effects
				(font
					(size 1.27 1.27)
				)
			)
		)
		(duplicate_pad_numbers_are_jumpers no)
		(fp_line
			(start 1.2954 0.5842)
			(end -1.2954 0.5842)
			(stroke
				(width 0.1524)
				(type default)
			)
			(layer "F.SilkS")
		)
		(fp_line
			(start 1.2954 -0.5842)
			(end 1.2954 0.5842)
			(stroke
				(width 0.1524)
				(type default)
			)
			(layer "F.SilkS")
		)
		(fp_line
			(start -1.2954 0.5842)
			(end -1.2954 -0.5842)
			(stroke
				(width 0.1524)
				(type default)
			)
			(layer "F.SilkS")
		)
		(fp_line
			(start -1.2954 -0.5842)
			(end 1.2954 -0.5842)
			(stroke
				(width 0.1524)
				(type default)
			)
			(layer "F.SilkS")
		)
		(fp_line
			(start 1.1938 0.4064)
			(end 0.8636 0.4064)
			(stroke
				(width 0.1)
				(type default)
			)
			(layer "F.Fab")
		)
		(fp_line
			(start 1.1938 -0.4064)
			(end 1.1938 0.4064)
			(stroke
				(width 0.1)
				(type default)
			)
			(layer "F.Fab")
		)
		(fp_line
			(start 0.8636 0.4572)
			(end -0.8636 0.4572)
			(stroke
				(width 0.1)
				(type default)
			)
			(layer "F.Fab")
		)
		(fp_line
			(start 0.8636 0.4064)
			(end 0.8636 0.4572)
			(stroke
				(width 0.1)
				(type default)
			)
			(layer "F.Fab")
		)
		(fp_line
			(start 0.8636 -0.4064)
			(end 1.1938 -0.4064)
			(stroke
				(width 0.1)
				(type default)
			)
			(layer "F.Fab")
		)
		(fp_line
			(start 0.8636 -0.4572)
			(end 0.8636 -0.4064)
			(stroke
				(width 0.1)
				(type default)
			)
			(layer "F.Fab")
		)
		(fp_line
			(start -0.8636 0.4572)
			(end -0.8636 0.4064)
			(stroke
				(width 0.1)
				(type default)
			)
			(layer "F.Fab")
		)
		(fp_line
			(start -0.8636 0.4064)
			(end -1.1938 0.4064)
			(stroke
				(width 0.1)
				(type default)
			)
			(layer "F.Fab")
		)
		(fp_line
			(start -0.8636 -0.4064)
			(end -0.8636 -0.4572)
			(stroke
				(width 0.1)
				(type default)
			)
			(layer "F.Fab")
		)
		(fp_line
			(start -0.8636 -0.4572)
			(end 0.8636 -0.4572)
			(stroke
				(width 0.1)
				(type default)
			)
			(layer "F.Fab")
		)
		(fp_line
			(start -1.1938 0.4064)
			(end -1.1938 -0.4064)
			(stroke
				(width 0.1)
				(type default)
			)
			(layer "F.Fab")
		)
		(fp_line
			(start -1.1938 -0.4064)
			(end -0.8636 -0.4064)
			(stroke
				(width 0.1)
				(type default)
			)
			(layer "F.Fab")
		)
		(pad "1" smd rect
			(at -0.7366 0 90)
			(size 0.7112 0.8128)
			(layers "F.Cu" "F.Mask" "F.Paste")
			(net "PCEPLL6_VDDA18_PEX1_R")
		)
		(pad "2" smd rect
			(at 0.7366 0 90)
			(size 0.7112 0.8128)
			(layers "F.Cu" "F.Mask" "F.Paste")
			(net "GND")
		)
	)
)
